FILE_TYPE=LIBRARY_PARTS;
primitive '74LVC1G07SE7';
  pin
    'VCC':
      PIN_NUMBER='(5)';
      PINUSE='POWER';
      NO_LOAD_CHECK='Both';
      NO_IO_CHECK='Both';
      NO_ASSERT_CHECK='TRUE';
      NO_DIR_CHECK='TRUE';
      ALLOW_CONNECT='TRUE';
    'A':
      PIN_NUMBER='(2)';
      INPUT_LOAD='(-0.01,0.01)';
    'GND':
      PIN_NUMBER='(3)';
      PINUSE='POWER';
      NO_LOAD_CHECK='Both';
      NO_IO_CHECK='Both';
      NO_ASSERT_CHECK='TRUE';
      NO_DIR_CHECK='TRUE';
      ALLOW_CONNECT='TRUE';
    'Y':
      PIN_NUMBER='(4)';
      OUTPUT_LOAD='(1.0,-1.0)';
    'NC1':
      PIN_NUMBER='(1)';
      OUTPUT_TYPE='(TS,TS)';
      INPUT_LOAD='(-0.01,0.01)';
      OUTPUT_LOAD='(1.0,-1.0)';
  end_pin;
  body
    PART_NAME='74LVC1G07SE7';
    BODY_NAME='74LVC1G07SE7';
    PHYS_DES_PREFIX='U';
    CLASS='IC';
  end_body;
end_primitive;

END.
